# SCM (Grand Teton) — schematic netlist excerpt (pin names and nets, part order shuffled) for the footprints in the layout excerpt that follows; sources: Cadence DE-HDL packaged netlist, KiCad conversion of 12092022_DA0F0TMDCD0_F0T_Management_Board_D_brd_V3_OCP.brd

C192  Q_CAP  0.1UF 25V 10% X7R  pkg 0402  page 26 : A = P3V3_AUX ; B = GND
R424  Q_RES  33.2 1% CHIP  pkg 0402LF  page 12 : A = SMB_BMC_MM13_R_SDA ; B = SMB_BMC_MM13_SDA

(kicad_pcb
	(version 20260206)
	(generator "pcbnew")
	(generator_version "10.0")
	(general
		(thickness 1.6)
		(legacy_teardrops no)
	)
	(paper "A4")
	(title_block
		(title "12092022_DA0F0TMDCD0_F0T_Management_Board_D_brd_V3_OCP.brd")
		(comment 1 "Grand Teton / footprints 830-831 of 1440")
	)
	(layers
		(0 "F.Cu" signal "TOP")
		(4 "In1.Cu" signal "GND")
		(6 "In2.Cu" signal "IN1")
		(8 "In3.Cu" signal "GND1")
		(10 "In4.Cu" signal "IN2")
		(12 "In5.Cu" signal "VCC")
		(14 "In6.Cu" signal "VCC1")
		(16 "In7.Cu" signal "IN3")
		(18 "In8.Cu" signal "GND2")
		(20 "In9.Cu" signal "IN4")
		(22 "In10.Cu" signal "GND3")
		(2 "B.Cu" signal "BOTTOM")
		(9 "F.Adhes" user "F.Adhesive")
		(11 "B.Adhes" user "B.Adhesive")
		(13 "F.Paste" user "Package Geometry/Pastemask Top")
		(15 "B.Paste" user "Package Geometry/Pastemask Bottom")
		(5 "F.SilkS" user "Ref Des/Silkscreen Top")
		(7 "B.SilkS" user "Ref Des/Silkscreen Bottom")
		(1 "F.Mask" user "Board Geometry/Soldermask Top")
		(3 "B.Mask" user "Board Geometry/Soldermask Bottom")
		(17 "Dwgs.User" user "User.Drawings")
		(19 "Cmts.User" user "User.Comments")
		(21 "Eco1.User" user "User.Eco1")
		(23 "Eco2.User" user "User.Eco2")
		(25 "Edge.Cuts" user "Board Geometry/Outline")
		(27 "Margin" user)
		(31 "F.CrtYd" user "Package Geometry/Place Bound Top")
		(29 "B.CrtYd" user "Package Geometry/Place Bound Bottom")
		(35 "F.Fab" user "Ref Des/Assembly Top")
		(33 "B.Fab" user "Ref Des/Assembly Bottom")
	)
	(footprint ""
		(layer "B.Cu")
		(at 71.069708 -29.817314)
		(property "Reference" "C192"
			(at 0 0 0)
			(layer "B.SilkS")
			(hide yes)
			(effects
				(font
					(size 1.27 1.27)
				)
				(justify mirror)
			)
		)
		(property "Value" ""
			(at 0 0 0)
			(layer "B.Fab")
			(effects
				(font
					(size 1.27 1.27)
				)
				(justify mirror)
			)
		)
		(duplicate_pad_numbers_are_jumpers no)
		(fp_line
			(start -0.7874 -0.4064)
			(end -0.7874 0.4064)
			(stroke
				(width 0.1524)
				(type default)
			)
			(layer "B.SilkS")
		)
		(fp_line
			(start -0.7874 0.4064)
			(end 0.7874 0.4064)
			(stroke
				(width 0.1524)
				(type default)
			)
			(layer "B.SilkS")
		)
		(fp_line
			(start 0.7874 -0.4064)
			(end -0.7874 -0.4064)
			(stroke
				(width 0.1524)
				(type default)
			)
			(layer "B.SilkS")
		)
		(fp_line
			(start 0.7874 0.4064)
			(end 0.7874 -0.4064)
			(stroke
				(width 0.1524)
				(type default)
			)
			(layer "B.SilkS")
		)
		(fp_line
			(start -0.67945 -0.3048)
			(end -0.67945 0.3048)
			(stroke
				(width 0.1)
				(type default)
			)
			(layer "B.Fab")
		)
		(fp_line
			(start -0.67945 0.3048)
			(end -0.120396 0.3048)
			(stroke
				(width 0.1)
				(type default)
			)
			(layer "B.Fab")
		)
		(fp_line
			(start -0.12065 -0.3048)
			(end -0.67945 -0.3048)
			(stroke
				(width 0.1)
				(type default)
			)
			(layer "B.Fab")
		)
		(fp_line
			(start -0.12065 -0.2794)
			(end -0.12065 -0.3048)
			(stroke
				(width 0.1)
				(type default)
			)
			(layer "B.Fab")
		)
		(fp_line
			(start -0.120396 0.2794)
			(end 0.12065 0.2794)
			(stroke
				(width 0.1)
				(type default)
			)
			(layer "B.Fab")
		)
		(fp_line
			(start -0.120396 0.3048)
			(end -0.120396 0.2794)
			(stroke
				(width 0.1)
				(type default)
			)
			(layer "B.Fab")
		)
		(fp_line
			(start 0.12065 -0.305054)
			(end 0.12065 -0.2794)
			(stroke
				(width 0.1)
				(type default)
			)
			(layer "B.Fab")
		)
		(fp_line
			(start 0.12065 -0.2794)
			(end -0.12065 -0.2794)
			(stroke
				(width 0.1)
				(type default)
			)
			(layer "B.Fab")
		)
		(fp_line
			(start 0.12065 0.2794)
			(end 0.12065 0.3048)
			(stroke
				(width 0.1)
				(type default)
			)
			(layer "B.Fab")
		)
		(fp_line
			(start 0.12065 0.3048)
			(end 0.67945 0.3048)
			(stroke
				(width 0.1)
				(type default)
			)
			(layer "B.Fab")
		)
		(fp_line
			(start 0.67945 -0.305054)
			(end 0.12065 -0.305054)
			(stroke
				(width 0.1)
				(type default)
			)
			(layer "B.Fab")
		)
		(fp_line
			(start 0.67945 0.3048)
			(end 0.67945 -0.305054)
			(stroke
				(width 0.1)
				(type default)
			)
			(layer "B.Fab")
		)
		(pad "1" smd circle
			(at 0.40005 0 180)
			(size 0 0)
			(layers "B.Cu" "B.Mask" "B.Paste")
			(net "P3V3_AUX")
		)
		(pad "2" smd circle
			(at -0.40005 0 180)
			(size 0 0)
			(layers "B.Cu" "B.Mask" "B.Paste")
			(net "GND")
		)
	)
	(footprint ""
		(layer "B.Cu")
		(at 39.930832 -48.026828)
		(property "Reference" "R424"
			(at 0 0 0)
			(layer "B.SilkS")
			(hide yes)
			(effects
				(font
					(size 1.27 1.27)
				)
				(justify mirror)
			)
		)
		(property "Value" ""
			(at 0 0 0)
			(layer "B.Fab")
			(effects
				(font
					(size 1.27 1.27)
				)
				(justify mirror)
			)
		)
		(duplicate_pad_numbers_are_jumpers no)
		(fp_line
			(start -0.7874 -0.4064)
			(end -0.7874 0.4064)
			(stroke
				(width 0.1524)
				(type default)
			)
			(layer "B.SilkS")
		)
		(fp_line
			(start -0.7874 0.4064)
			(end 0.7874 0.4064)
			(stroke
				(width 0.1524)
				(type default)
			)
			(layer "B.SilkS")
		)
		(fp_line
			(start 0.7874 -0.4064)
			(end -0.7874 -0.4064)
			(stroke
				(width 0.1524)
				(type default)
			)
			(layer "B.SilkS")
		)
		(fp_line
			(start 0.7874 0.4064)
			(end 0.7874 -0.4064)
			(stroke
				(width 0.1524)
				(type default)
			)
			(layer "B.SilkS")
		)
		(fp_line
			(start -0.67945 -0.3048)
			(end -0.67945 0.3048)
			(stroke
				(width 0.1)
				(type default)
			)
			(layer "B.Fab")
		)
		(fp_line
			(start -0.67945 0.3048)
			(end -0.120396 0.3048)
			(stroke
				(width 0.1)
				(type default)
			)
			(layer "B.Fab")
		)
		(fp_line
			(start -0.12065 -0.3048)
			(end -0.67945 -0.3048)
			(stroke
				(width 0.1)
				(type default)
			)
			(layer "B.Fab")
		)
		(fp_line
			(start -0.12065 -0.2794)
			(end -0.12065 -0.3048)
			(stroke
				(width 0.1)
				(type default)
			)
			(layer "B.Fab")
		)
		(fp_line
			(start -0.120396 0.2794)
			(end 0.12065 0.2794)
			(stroke
				(width 0.1)
				(type default)
			)
			(layer "B.Fab")
		)
		(fp_line
			(start -0.120396 0.3048)
			(end -0.120396 0.2794)
			(stroke
				(width 0.1)
				(type default)
			)
			(layer "B.Fab")
		)
		(fp_line
			(start 0.12065 -0.305054)
			(end 0.12065 -0.2794)
			(stroke
				(width 0.1)
				(type default)
			)
			(layer "B.Fab")
		)
		(fp_line
			(start 0.12065 -0.2794)
			(end -0.12065 -0.2794)
			(stroke
				(width 0.1)
				(type default)
			)
			(layer "B.Fab")
		)
		(fp_line
			(start 0.12065 0.2794)
			(end 0.12065 0.3048)
			(stroke
				(width 0.1)
				(type default)
			)
			(layer "B.Fab")
		)
		(fp_line
			(start 0.12065 0.3048)
			(end 0.67945 0.3048)
			(stroke
				(width 0.1)
				(type default)
			)
			(layer "B.Fab")
		)
		(fp_line
			(start 0.67945 -0.305054)
			(end 0.12065 -0.305054)
			(stroke
				(width 0.1)
				(type default)
			)
			(layer "B.Fab")
		)
		(fp_line
			(start 0.67945 0.3048)
			(end 0.67945 -0.305054)
			(stroke
				(width 0.1)
				(type default)
			)
			(layer "B.Fab")
		)
		(pad "1" smd circle
			(at 0.40005 0 180)
			(size 0 0)
			(layers "B.Cu" "B.Mask" "B.Paste")
			(net "SMB_BMC_MM13_R_SDA")
		)
		(pad "2" smd circle
			(at -0.40005 0 180)
			(size 0 0)
			(layers "B.Cu" "B.Mask" "B.Paste")
			(net "SMB_BMC_MM13_SDA")
		)
	)
)
